(kicad_pcb
	(version 20260206)
	(generator "pcbnew")
	(generator_version "10.0")
	(general
		(thickness 1.6)
		(legacy_teardrops no)
	)
	(paper "A4")
	(title_block
		(title "peb — Lightning_PEB_BRD.brd")
		(comment 1 "Lightning (Wiwynn / Facebook NVMe JBOF) / footprints 2328-2335 of 2563")
	)
	(layers
		(0 "F.Cu" signal "TOP")
		(4 "In1.Cu" signal "L2GND")
		(6 "In2.Cu" signal "L3")
		(8 "In3.Cu" signal "L4VCC")
		(10 "In4.Cu" signal "L5VCC")
		(12 "In5.Cu" signal "L6")
		(14 "In6.Cu" signal "L7GND")
		(2 "B.Cu" signal "BOTTOM")
		(9 "F.Adhes" user "F.Adhesive")
		(11 "B.Adhes" user "B.Adhesive")
		(13 "F.Paste" user "Package Geometry/Pastemask Top")
		(15 "B.Paste" user "Package Geometry/Pastemask Bottom")
		(5 "F.SilkS" user "Ref Des/Silkscreen Top")
		(7 "B.SilkS" user "Ref Des/Silkscreen Bottom")
		(1 "F.Mask" user "Board Geometry/Soldermask Top")
		(3 "B.Mask" user "Board Geometry/Soldermask Bottom")
		(17 "Dwgs.User" user "User.Drawings")
		(19 "Cmts.User" user "User.Comments")
		(21 "Eco1.User" user "User.Eco1")
		(23 "Eco2.User" user "User.Eco2")
		(25 "Edge.Cuts" user "Board Geometry/Outline")
		(27 "Margin" user)
		(31 "F.CrtYd" user "Package Geometry/Place Bound Top")
		(29 "B.CrtYd" user "Package Geometry/Place Bound Bottom")
		(35 "F.Fab" user "Ref Des/Assembly Top")
		(33 "B.Fab" user "Ref Des/Assembly Bottom")
	)
	(footprint ""
		(layer "B.Cu")
		(at 10.922 -107.188 90)
		(property "Reference" "PC85"
			(at 0 0 90)
			(layer "B.SilkS")
			(hide yes)
			(effects
				(font
					(size 1.27 1.27)
				)
				(justify mirror)
			)
		)
		(property "Value" "SCD01U25V2KX-3GP"
			(at -1.1811 -2.7051 90)
			(unlocked yes)
			(layer "B.Fab")
			(hide yes)
			(effects
				(font
					(size 1.016 1.016)
					(thickness 0.1524)
				)
				(justify mirror)
			)
		)
		(property "Device Type" "C402H22"
			(at -1.1811 -4.2291 90)
			(unlocked yes)
			(layer "B.Fab")
			(hide yes)
			(effects
				(font
					(size 1.016 1.016)
					(thickness 0.1524)
				)
				(justify mirror)
			)
		)
		(duplicate_pad_numbers_are_jumpers no)
		(fp_rect
			(start 0.4318 0.9525)
			(end -0.4318 -0.9525)
			(stroke
				(width 0)
				(type default)
			)
			(fill no)
			(layer "B.CrtYd")
		)
		(fp_rect
			(start 0.4318 0.9525)
			(end -0.4318 -0.9525)
			(stroke
				(width 0)
				(type default)
			)
			(fill no)
			(layer "B.Fab")
		)
		(pad "1" smd custom
			(at 0 -0.4445 270)
			(size 0.1524 0.1524)
			(layers "B.Cu" "B.Mask" "B.Paste")
			(net "VR_P1V26_STBY_EN_R")
			(options
				(clearance outline)
				(anchor circle)
			)
			(primitives
				(gr_poly
					(pts
						(arc
							(start 0.3048 0.2032)
							(mid 0.275042 0.275042)
							(end 0.2032 0.3048)
						)
						(arc
							(start -0.2032 0.3048)
							(mid -0.275042 0.275042)
							(end -0.3048 0.2032)
						)
						(arc
							(start -0.3048 -0.2032)
							(mid -0.275042 -0.275042)
							(end -0.2032 -0.3048)
						)
						(arc
							(start 0.2032 -0.3048)
							(mid 0.275042 -0.275042)
							(end 0.3048 -0.2032)
						)
					)
					(width 0)
					(fill yes)
				)
			)
		)
		(pad "2" smd custom
			(at 0 0.4445 270)
			(size 0.1524 0.1524)
			(layers "B.Cu" "B.Mask" "B.Paste")
			(net "GND")
			(options
				(clearance outline)
				(anchor circle)
			)
			(primitives
				(gr_poly
					(pts
						(arc
							(start 0.3048 0.2032)
							(mid 0.275042 0.275042)
							(end 0.2032 0.3048)
						)
						(arc
							(start -0.2032 0.3048)
							(mid -0.275042 0.275042)
							(end -0.3048 0.2032)
						)
						(arc
							(start -0.3048 -0.2032)
							(mid -0.275042 -0.275042)
							(end -0.2032 -0.3048)
						)
						(arc
							(start 0.2032 -0.3048)
							(mid 0.275042 -0.275042)
							(end 0.3048 -0.2032)
						)
					)
					(width 0)
					(fill yes)
				)
			)
		)
	)
	(footprint ""
		(layer "B.Cu")
		(at 136.652 -202.819)
		(property "Reference" "U70"
			(at 0 0 0)
			(layer "B.SilkS")
			(hide yes)
			(effects
				(font
					(size 1.27 1.27)
				)
				(justify mirror)
			)
		)
		(property "Value" "SN74LVC1G08DCKR-GP"
			(at 2.3368 -8.6868 0)
			(unlocked yes)
			(layer "B.Fab")
			(hide yes)
			(effects
				(font
					(size 1.016 1.016)
					(thickness 0.1524)
				)
				(justify mirror)
			)
		)
		(property "Device Type" "SC70-5H44"
			(at 2.3114 -10.414 0)
			(unlocked yes)
			(layer "B.Fab")
			(hide yes)
			(effects
				(font
					(size 1.016 1.016)
					(thickness 0.1524)
				)
				(justify mirror)
			)
		)
		(duplicate_pad_numbers_are_jumpers no)
		(fp_line
			(start -1.3843 -1.8034)
			(end -1.3843 -1.1176)
			(stroke
				(width 0.3302)
				(type default)
			)
			(layer "B.SilkS")
		)
		(fp_line
			(start -1.27 -1.7018)
			(end -1.27 1.7018)
			(stroke
				(width 0.1524)
				(type default)
			)
			(layer "B.SilkS")
		)
		(fp_line
			(start -1.27 1.7018)
			(end 1.27 1.7018)
			(stroke
				(width 0.1524)
				(type default)
			)
			(layer "B.SilkS")
		)
		(fp_line
			(start -0.6604 -1.8034)
			(end -1.3843 -1.8034)
			(stroke
				(width 0.3302)
				(type default)
			)
			(layer "B.SilkS")
		)
		(fp_line
			(start 1.27 -1.7018)
			(end -1.27 -1.7018)
			(stroke
				(width 0.1524)
				(type default)
			)
			(layer "B.SilkS")
		)
		(fp_line
			(start 1.27 1.7018)
			(end 1.27 -1.7018)
			(stroke
				(width 0.1524)
				(type default)
			)
			(layer "B.SilkS")
		)
		(fp_rect
			(start 1.524 1.9558)
			(end -1.524 -1.9558)
			(stroke
				(width 0)
				(type default)
			)
			(fill no)
			(layer "B.CrtYd")
		)
		(fp_poly
			(pts
				(xy 1.524 -1.9558) (xy -1.524 -1.9558) (xy -1.524 1.9558) (xy 1.524 1.9558)
			)
			(stroke
				(width 0)
				(type default)
			)
			(fill no)
			(layer "B.Fab")
		)
		(pad "1" smd rect
			(at -0.65024 -0.8255 180)
			(size 0.4064 1.2192)
			(layers "B.Cu" "B.Mask" "B.Paste")
			(net "BMC_SSD_RST#0_A6")
		)
		(pad "2" smd rect
			(at 0 -0.8255 180)
			(size 0.4064 1.2192)
			(layers "B.Cu" "B.Mask" "B.Paste")
			(net "SSD_PERST#0_B6")
		)
		(pad "3" smd rect
			(at 0.65024 -0.8255 180)
			(size 0.4064 1.2192)
			(layers "B.Cu" "B.Mask" "B.Paste")
			(net "GND")
		)
		(pad "4" smd rect
			(at 0.65024 0.8255 180)
			(size 0.4064 1.2192)
			(layers "B.Cu" "B.Mask" "B.Paste")
			(net "SSD_PERST_Y6")
		)
		(pad "5" smd rect
			(at -0.65024 0.8255 180)
			(size 0.4064 1.2192)
			(layers "B.Cu" "B.Mask" "B.Paste")
			(net "P3V3_STBY")
		)
	)
	(footprint ""
		(layer "B.Cu")
		(at 336.5246 -175.7426)
		(property "Reference" "C3206"
			(at 0 0 0)
			(layer "B.SilkS")
			(hide yes)
			(effects
				(font
					(size 1.27 1.27)
				)
				(justify mirror)
			)
		)
		(property "Value" "SCD1U25V2KX-2-GP"
			(at -1.1811 -2.7051 0)
			(unlocked yes)
			(layer "B.Fab")
			(hide yes)
			(effects
				(font
					(size 1.016 1.016)
					(thickness 0.1524)
				)
				(justify mirror)
			)
		)
		(property "Device Type" "C402H22"
			(at -1.1811 -4.2291 0)
			(unlocked yes)
			(layer "B.Fab")
			(hide yes)
			(effects
				(font
					(size 1.016 1.016)
					(thickness 0.1524)
				)
				(justify mirror)
			)
		)
		(duplicate_pad_numbers_are_jumpers no)
		(fp_rect
			(start 0.4318 0.9525)
			(end -0.4318 -0.9525)
			(stroke
				(width 0)
				(type default)
			)
			(fill no)
			(layer "B.CrtYd")
		)
		(fp_rect
			(start 0.4318 0.9525)
			(end -0.4318 -0.9525)
			(stroke
				(width 0)
				(type default)
			)
			(fill no)
			(layer "B.Fab")
		)
		(pad "1" smd custom
			(at 0 -0.4445 180)
			(size 0.1524 0.1524)
			(layers "B.Cu" "B.Mask" "B.Paste")
			(net "P3V3_STBY")
			(options
				(clearance outline)
				(anchor circle)
			)
			(primitives
				(gr_poly
					(pts
						(arc
							(start 0.3048 0.2032)
							(mid 0.275042 0.275042)
							(end 0.2032 0.3048)
						)
						(arc
							(start -0.2032 0.3048)
							(mid -0.275042 0.275042)
							(end -0.3048 0.2032)
						)
						(arc
							(start -0.3048 -0.2032)
							(mid -0.275042 -0.275042)
							(end -0.2032 -0.3048)
						)
						(arc
							(start 0.2032 -0.3048)
							(mid 0.275042 -0.275042)
							(end 0.3048 -0.2032)
						)
					)
					(width 0)
					(fill yes)
				)
			)
		)
		(pad "2" smd custom
			(at 0 0.4445 180)
			(size 0.1524 0.1524)
			(layers "B.Cu" "B.Mask" "B.Paste")
			(net "GND")
			(options
				(clearance outline)
				(anchor circle)
			)
			(primitives
				(gr_poly
					(pts
						(arc
							(start 0.3048 0.2032)
							(mid 0.275042 0.275042)
							(end 0.2032 0.3048)
						)
						(arc
							(start -0.2032 0.3048)
							(mid -0.275042 0.275042)
							(end -0.3048 0.2032)
						)
						(arc
							(start -0.3048 -0.2032)
							(mid -0.275042 -0.275042)
							(end -0.2032 -0.3048)
						)
						(arc
							(start 0.2032 -0.3048)
							(mid 0.275042 -0.275042)
							(end 0.3048 -0.2032)
						)
					)
					(width 0)
					(fill yes)
				)
			)
		)
	)
	(footprint ""
		(layer "B.Cu")
		(at 13.506958 -75.786234 90)
		(property "Reference" "C622"
			(at 0 0 90)
			(layer "B.SilkS")
			(hide yes)
			(effects
				(font
					(size 1.27 1.27)
				)
				(justify mirror)
			)
		)
		(property "Value" "SCD1U16V2KX-3GP"
			(at -1.1811 -2.7051 90)
			(unlocked yes)
			(layer "B.Fab")
			(hide yes)
			(effects
				(font
					(size 1.016 1.016)
					(thickness 0.1524)
				)
				(justify mirror)
			)
		)
		(property "Device Type" "C402H22"
			(at -1.1811 -4.2291 90)
			(unlocked yes)
			(layer "B.Fab")
			(hide yes)
			(effects
				(font
					(size 1.016 1.016)
					(thickness 0.1524)
				)
				(justify mirror)
			)
		)
		(duplicate_pad_numbers_are_jumpers no)
		(fp_rect
			(start 0.4318 0.9525)
			(end -0.4318 -0.9525)
			(stroke
				(width 0)
				(type default)
			)
			(fill no)
			(layer "B.CrtYd")
		)
		(fp_rect
			(start 0.4318 0.9525)
			(end -0.4318 -0.9525)
			(stroke
				(width 0)
				(type default)
			)
			(fill no)
			(layer "B.Fab")
		)
		(pad "1" smd custom
			(at 0 -0.4445 270)
			(size 0.1524 0.1524)
			(layers "B.Cu" "B.Mask" "B.Paste")
			(net "P1V5_I210")
			(options
				(clearance outline)
				(anchor circle)
			)
			(primitives
				(gr_poly
					(pts
						(arc
							(start 0.3048 0.2032)
							(mid 0.275042 0.275042)
							(end 0.2032 0.3048)
						)
						(arc
							(start -0.2032 0.3048)
							(mid -0.275042 0.275042)
							(end -0.3048 0.2032)
						)
						(arc
							(start -0.3048 -0.2032)
							(mid -0.275042 -0.275042)
							(end -0.2032 -0.3048)
						)
						(arc
							(start 0.2032 -0.3048)
							(mid 0.275042 -0.275042)
							(end 0.3048 -0.2032)
						)
					)
					(width 0)
					(fill yes)
				)
			)
		)
		(pad "2" smd custom
			(at 0 0.4445 270)
			(size 0.1524 0.1524)
			(layers "B.Cu" "B.Mask" "B.Paste")
			(net "GND")
			(options
				(clearance outline)
				(anchor circle)
			)
			(primitives
				(gr_poly
					(pts
						(arc
							(start 0.3048 0.2032)
							(mid 0.275042 0.275042)
							(end 0.2032 0.3048)
						)
						(arc
							(start -0.2032 0.3048)
							(mid -0.275042 0.275042)
							(end -0.3048 0.2032)
						)
						(arc
							(start -0.3048 -0.2032)
							(mid -0.275042 -0.275042)
							(end -0.2032 -0.3048)
						)
						(arc
							(start 0.2032 -0.3048)
							(mid 0.275042 -0.275042)
							(end 0.3048 -0.2032)
						)
					)
					(width 0)
					(fill yes)
				)
			)
		)
	)
	(footprint ""
		(layer "B.Cu")
		(at 50.292 -125.349)
		(property "Reference" "TP180"
			(at 0 0 0)
			(layer "B.SilkS")
			(hide yes)
			(effects
				(font
					(size 1.27 1.27)
				)
				(justify mirror)
			)
		)
		(property "Value" "TPAD28-2-GP"
			(at 0.0127 -1.6637 0)
			(unlocked yes)
			(layer "B.Fab")
			(hide yes)
			(effects
				(font
					(size 1.016 1.016)
					(thickness 0.1524)
				)
				(justify mirror)
			)
		)
		(property "Device Type" "TPAD28"
			(at 0.0127 -3.1877 0)
			(unlocked yes)
			(layer "B.Fab")
			(hide yes)
			(effects
				(font
					(size 1.016 1.016)
					(thickness 0.1524)
				)
				(justify mirror)
			)
		)
		(duplicate_pad_numbers_are_jumpers no)
		(fp_poly
			(pts
				(arc
					(start 0.3556 0)
					(mid -0.3556 0)
					(end 0.3556 0)
				)
			)
			(stroke
				(width 0)
				(type default)
			)
			(fill no)
			(layer "B.CrtYd")
		)
		(fp_poly
			(pts
				(arc
					(start 0.6096 0)
					(mid -0.6096 0)
					(end 0.6096 0)
				)
			)
			(stroke
				(width 0)
				(type default)
			)
			(fill no)
			(layer "B.Fab")
		)
		(pad "1" smd circle
			(at 0 0 180)
			(size 0.7112 0.7112)
			(layers "B.Cu" "B.Mask" "B.Paste")
			(net "JTAG_BMC_TDO")
		)
	)
	(footprint ""
		(layer "B.Cu")
		(at 18.3134 -69.1134 180)
		(property "Reference" "R425"
			(at 0 0 0)
			(layer "B.SilkS")
			(hide yes)
			(effects
				(font
					(size 1.27 1.27)
				)
				(justify mirror)
			)
		)
		(property "Value" "0R3J-0-U-GP"
			(at 0.0254 -2.5146 180)
			(unlocked yes)
			(layer "B.Fab")
			(hide yes)
			(effects
				(font
					(size 1.016 1.016)
					(thickness 0.1524)
				)
				(justify mirror)
			)
		)
		(property "Device Type" "R603H22"
			(at 0.0254 -4.0386 180)
			(unlocked yes)
			(layer "B.Fab")
			(hide yes)
			(effects
				(font
					(size 1.016 1.016)
					(thickness 0.1524)
				)
				(justify mirror)
			)
		)
		(duplicate_pad_numbers_are_jumpers no)
		(fp_line
			(start 0.4826 0)
			(end 0.2032 0)
			(stroke
				(width 0.2032)
				(type default)
			)
			(layer "B.SilkS")
		)
		(fp_line
			(start -0.2032 0)
			(end -0.4826 0)
			(stroke
				(width 0.2032)
				(type default)
			)
			(layer "B.SilkS")
		)
		(fp_rect
			(start 0.5842 1.3335)
			(end -0.5842 -1.3335)
			(stroke
				(width 0)
				(type default)
			)
			(fill no)
			(layer "B.CrtYd")
		)
		(fp_rect
			(start 0.5842 1.3335)
			(end -0.5842 -1.3335)
			(stroke
				(width 0)
				(type default)
			)
			(fill no)
			(layer "B.Fab")
		)
		(pad "1" smd custom
			(at 0 -0.762)
			(size 0.2159 0.2159)
			(layers "B.Cu" "B.Mask" "B.Paste")
			(net "P3V3_STBY")
			(options
				(clearance outline)
				(anchor circle)
			)
			(primitives
				(gr_poly
					(pts
						(arc
							(start -0.3302 0.4318)
							(mid -0.402042 0.402042)
							(end -0.4318 0.3302)
						)
						(arc
							(start -0.4318 -0.3302)
							(mid -0.402042 -0.402042)
							(end -0.3302 -0.4318)
						)
						(arc
							(start 0.3302 -0.4318)
							(mid 0.402042 -0.402042)
							(end 0.4318 -0.3302)
						)
						(arc
							(start 0.4318 0.3302)
							(mid 0.402042 0.402042)
							(end 0.3302 0.4318)
						)
					)
					(width 0)
					(fill yes)
				)
			)
		)
		(pad "2" smd custom
			(at 0 0.762)
			(size 0.2159 0.2159)
			(layers "B.Cu" "B.Mask" "B.Paste")
			(net "LAN1_51")
			(options
				(clearance outline)
				(anchor circle)
			)
			(primitives
				(gr_poly
					(pts
						(arc
							(start -0.3302 0.4318)
							(mid -0.402042 0.402042)
							(end -0.4318 0.3302)
						)
						(arc
							(start -0.4318 -0.3302)
							(mid -0.402042 -0.402042)
							(end -0.3302 -0.4318)
						)
						(arc
							(start 0.3302 -0.4318)
							(mid 0.402042 -0.402042)
							(end 0.4318 -0.3302)
						)
						(arc
							(start 0.4318 0.3302)
							(mid 0.402042 0.402042)
							(end 0.3302 0.4318)
						)
					)
					(width 0)
					(fill yes)
				)
			)
		)
	)
	(footprint ""
		(layer "B.Cu")
		(at 264.19556 -2.352802 180)
		(property "Reference" "R202"
			(at 0 0 0)
			(layer "B.SilkS")
			(hide yes)
			(effects
				(font
					(size 1.27 1.27)
				)
				(justify mirror)
			)
		)
		(property "Value" "49D9R2D-GP"
			(at -0.064008 -3.993896 180)
			(unlocked yes)
			(layer "B.Fab")
			(hide yes)
			(effects
				(font
					(size 1.016 1.016)
					(thickness 0.1524)
				)
				(justify mirror)
			)
		)
		(property "Device Type" "R402H16"
			(at -0.064008 -5.517896 180)
			(unlocked yes)
			(layer "B.Fab")
			(hide yes)
			(effects
				(font
					(size 1.016 1.016)
					(thickness 0.1524)
				)
				(justify mirror)
			)
		)
		(duplicate_pad_numbers_are_jumpers no)
		(fp_line
			(start 0.508 -0.9398)
			(end 0.508 0.9398)
			(stroke
				(width 0.1524)
				(type default)
			)
			(layer "B.SilkS")
		)
		(fp_line
			(start -0.508 -0.9398)
			(end 0.508 -0.9398)
			(stroke
				(width 0.1524)
				(type default)
			)
			(layer "B.SilkS")
		)
		(fp_rect
			(start 0.508 0.9398)
			(end -0.508 -0.9398)
			(stroke
				(width 0)
				(type default)
			)
			(fill no)
			(layer "B.CrtYd")
		)
		(fp_rect
			(start 0.508 0.9398)
			(end -0.508 -0.9398)
			(stroke
				(width 0)
				(type default)
			)
			(fill no)
			(layer "B.Fab")
		)
		(pad "1" smd custom
			(at 0 -0.4445)
			(size 0.1397 0.1397)
			(layers "B.Cu" "B.Mask" "B.Paste")
			(net "TEMP_SENSOR_DXN_BJT")
			(options
				(clearance outline)
				(anchor circle)
			)
			(primitives
				(gr_poly
					(pts
						(arc
							(start -0.1778 0.2794)
							(mid -0.249642 0.249642)
							(end -0.2794 0.1778)
						)
						(arc
							(start -0.2794 -0.1778)
							(mid -0.249642 -0.249642)
							(end -0.1778 -0.2794)
						)
						(arc
							(start 0.1778 -0.2794)
							(mid 0.249642 -0.249642)
							(end 0.2794 -0.1778)
						)
						(arc
							(start 0.2794 0.1778)
							(mid 0.249642 0.249642)
							(end 0.1778 0.2794)
						)
					)
					(width 0)
					(fill yes)
				)
			)
		)
		(pad "2" smd custom
			(at 0 0.4445)
			(size 0.1397 0.1397)
			(layers "B.Cu" "B.Mask" "B.Paste")
			(net "TEMP_SENSOR_DXN")
			(options
				(clearance outline)
				(anchor circle)
			)
			(primitives
				(gr_poly
					(pts
						(arc
							(start -0.1778 0.2794)
							(mid -0.249642 0.249642)
							(end -0.2794 0.1778)
						)
						(arc
							(start -0.2794 -0.1778)
							(mid -0.249642 -0.249642)
							(end -0.1778 -0.2794)
						)
						(arc
							(start 0.1778 -0.2794)
							(mid 0.249642 -0.249642)
							(end 0.2794 -0.1778)
						)
						(arc
							(start 0.2794 0.1778)
							(mid 0.249642 0.249642)
							(end 0.1778 0.2794)
						)
					)
					(width 0)
					(fill yes)
				)
			)
		)
	)
	(footprint ""
		(layer "B.Cu")
		(at 56.092852 -110.14583)
		(property "Reference" "R327"
			(at 0 0 0)
			(layer "B.SilkS")
			(hide yes)
			(effects
				(font
					(size 1.27 1.27)
				)
				(justify mirror)
			)
		)
		(property "Value" "4K7R2F-GP"
			(at -0.064008 -3.993896 0)
			(unlocked yes)
			(layer "B.Fab")
			(hide yes)
			(effects
				(font
					(size 1.016 1.016)
					(thickness 0.1524)
				)
				(justify mirror)
			)
		)
		(property "Device Type" "R402H16"
			(at -0.064008 -5.517896 0)
			(unlocked yes)
			(layer "B.Fab")
			(hide yes)
			(effects
				(font
					(size 1.016 1.016)
					(thickness 0.1524)
				)
				(justify mirror)
			)
		)
		(duplicate_pad_numbers_are_jumpers no)
		(fp_line
			(start -0.508 -0.9398)
			(end 0.508 -0.9398)
			(stroke
				(width 0.1524)
				(type default)
			)
			(layer "B.SilkS")
		)
		(fp_line
			(start 0.508 -0.9398)
			(end 0.508 0.9398)
			(stroke
				(width 0.1524)
				(type default)
			)
			(layer "B.SilkS")
		)
		(fp_rect
			(start 0.508 0.9398)
			(end -0.508 -0.9398)
			(stroke
				(width 0)
				(type default)
			)
			(fill no)
			(layer "B.CrtYd")
		)
		(fp_rect
			(start 0.508 0.9398)
			(end -0.508 -0.9398)
			(stroke
				(width 0)
				(type default)
			)
			(fill no)
			(layer "B.Fab")
		)
		(pad "1" smd custom
			(at 0 -0.4445 180)
			(size 0.1397 0.1397)
			(layers "B.Cu" "B.Mask" "B.Paste")
			(net "P3V3_STBY")
			(options
				(clearance outline)
				(anchor circle)
			)
			(primitives
				(gr_poly
					(pts
						(arc
							(start -0.1778 0.2794)
							(mid -0.249642 0.249642)
							(end -0.2794 0.1778)
						)
						(arc
							(start -0.2794 -0.1778)
							(mid -0.249642 -0.249642)
							(end -0.1778 -0.2794)
						)
						(arc
							(start 0.1778 -0.2794)
							(mid 0.249642 -0.249642)
							(end 0.2794 -0.1778)
						)
						(arc
							(start 0.2794 0.1778)
							(mid 0.249642 0.249642)
							(end 0.1778 0.2794)
						)
					)
					(width 0)
					(fill yes)
				)
			)
		)
		(pad "2" smd custom
			(at 0 0.4445 180)
			(size 0.1397 0.1397)
			(layers "B.Cu" "B.Mask" "B.Paste")
			(net "I2C6_LS_G1")
			(options
				(clearance outline)
				(anchor circle)
			)
			(primitives
				(gr_poly
					(pts
						(arc
							(start -0.1778 0.2794)
							(mid -0.249642 0.249642)
							(end -0.2794 0.1778)
						)
						(arc
							(start -0.2794 -0.1778)
							(mid -0.249642 -0.249642)
							(end -0.1778 -0.2794)
						)
						(arc
							(start 0.1778 -0.2794)
							(mid 0.249642 -0.249642)
							(end 0.2794 -0.1778)
						)
						(arc
							(start 0.2794 0.1778)
							(mid 0.249642 0.249642)
							(end 0.1778 0.2794)
						)
					)
					(width 0)
					(fill yes)
				)
			)
		)
	)
)
